 
 
Open CloudServer OCS 
NIC Mezzanine Specification 
Version 2.0 
 
 
 
 
 
Author: 
Mark Shaw, Director of Hardware Engineering, Microsoft 
 



Open Compute Project  Open CloudServer OCS NIC Mezzanine 
http://opencompute.org ii 
Revision History 
Date Description 
10/10/2014 Version 2.0 
 
  



Open Compute Project  Open CloudServer OCS NIC Mezzanine 
http://opencompute.org iii 
 
© 2014 Microsoft Corporation. 
As of October 30, 2014, the following persons or entities have made this Specification available under the Open Web 
Foundation Final Specification Agreement (OWFa 1.0), which is available at http://www.openwebfoundation.org/legal/the-owf-
1-0-agreements/owfa-1-0 
Microsoft Corporation.  
You can review the signed copies of the Open Web Foundation Agreement Version 1.0 for this Specification at 
http://opencompute.org/licensing/, which may also include additional parties to those listed above. 
Your use of this Specification may be subject to other third party rights. THIS SPECIFICATION IS PROVIDED "AS IS." The 
contributors expressly disclaim any warranties (express, implied, or otherwise), including implied warranties of merchantability, 
noninfringement, fitness for a particular purpose, or title, related to the Specification. The entire risk as to implementing or 
otherwise using the Specification is assumed by the Specification implementer and user. IN NO EVENT WILL ANY PARTY BE 
LIABLE TO ANY OTHER PARTY FOR LOST PROFITS OR ANY FORM OF INDIRECT, SPECIAL, INCIDENTAL, OR CONSEQUENTIAL 
DAMAGES OF ANY CHARACTER FROM ANY CAUSES OF ACTION OF ANY KIND WITH RESPECT TO THIS SPECIFICATION OR ITS 
GOVERNING AGREEMENT, WHETHER BASED ON BREACH OF CONTRACT, TORT (INCLUDING NEGLIGENCE), OR OTHERWISE, AND 
WHETHER OR NOT THE OTHER PARTY HAS BEEN ADVISED OF THE POSSIBILITY OF SUCH DAMAGE. 
CONTRIBUTORS AND LICENSORS OF THIS SPECIFICATION MAY HAVE MENTIONED CERTAIN TECHNOLOGIES THAT ARE MERELY 
REFERENCED WITHIN THIS SPECIFICATION AND NOT LICENSED UNDER THE OWF CLA OR OWFa. THE FOLLOWING IS A LIST OF 
MERELY REFERENCED TECHNOLOGY: INTELLIGENT PLATFORM MANAGEMENT INTERFACE (IPMI), I2C TRADEMARK OF PHILLIPS 
SEMICONDUCTOR. IMPLEMENTATION OF THESE TECHNOLOGIES MAY BE SUBJECT TO THEIR OWN LEGAL TERMS.  



 
iv October 30, 2014 
 
 
Contents 
1 Summary ....................................................................................................................................................... 1 
1.1 Block Diagram .............................................................................................................................................. 1 
1.2 Interface Topology ....................................................................................................................................... 1 
2 Interface Connector ....................................................................................................................................... 2 
2.1 Signal Definitions .......................................................................................................................................... 2 
2.2 Connector Pinout .......................................................................................................................................... 5 
2.3 Retimers/Repeaters ...................................................................................................................................... 6 
2.4 Power ........................................................................................................................................................... 6 
3 Mechanical Control Outline ........................................................................................................................... 7 
4 CAD Model Capture ....................................................................................................................................... 7 
5 Thermal ......................................................................................................................................................... 8 
6 Standoffs and Screws for Assembly ............................................................................................................... 8 
 
Table of Figures 
Figure 1: NIC mezzanine block diagram ........................................................................................................ 1 
Figure 2: Connector stackup example .......................................................................................................... 2 
Figure 3: NIC mezzanine power-up sequence .............................................................................................. 6 
Figure 4: Mechanical control outline for the NIC mezzanine card ............................................................... 7 
Figure 5: NIC mezzanine, installed ................................................................................................................ 8 
Table of Tables 
Table 1: Connector manufacturing part numbers ........................................................................................ 2 
Table 2: NIC mezzanine connector signal definitions ................................................................................... 3 
Table 3: NIC mezzanine connector pinout .................................................................................................... 5 
Table 4: NIC mezzanine power ratings ......................................................................................................... 6 
 
 



Open Compute Project  Open CloudServer OCS NIC Mezzanine 
http://opencompute.org 1 
1 Summary 
This specification, Open CloudServer NIC Mezzanine Version 2.0, describes the physical and 
interface requirements for the Open CloudServer (OCS) NIC mezzanine card that to be installed on 
an OCS blade.   
Note that this specification does not cover the functional or features requirements for the 
mezzanine cards that will be developed for this project. 
1.1 Block Diagram 
The mezzanine card will be installed on the blade and will have a Peripheral Component 
Interconnect Express (PCIe) x8 Gen3 interface to a central processing unit (CPU) on the blade 
motherboard. It will support either a single 10Gigabit Ethernet (GbE) to a small form-factor 
pluggable (SFP)+ cable or a single 40GbE interface to a quad small form-factor pluggable (QSFP)+ 
cable. It is never required to support both interfaces on the same mezzanine card.   
To maintain compatibility with existing mezzanine designs, the 10GbE port must map to network 
port 1 on the SEAF/SEAM connector interface, and the 40GbE port must map to network port 2 on 
the SEAF/SEAM connector interface. Figure 1 shows a block diagram of the interface. 
Blade Motherboard
  
 NIC Mezz
Tray Backplane
Airmax
VS2
Airmax
VS2     NWK2
     Controller
     40GbE
10GbE Port
40GbE Port
SEAM SEAF
Port 2
Port 1
L0
L1
L2
L3
L0
L1
L2
L3
Retimer
DS110DF111
    NWK1
    Controller
    10GbE
L2
L3
L1
L0
L0 L0
L1
L2
L3
L0
L1
L2
L3
Port 2
Port 1
Network
SwitchCable
< 3m
Network
SwitchCable
< 3m<1.6"<3.5"
<1"
<0.9"
SFP+
QSFP+
L3
L2
L1
L0
L0
PCIe x8
CPU
PCIe PCIe
NCSI BMCNCSI NCSI
 
Figure 1: NIC mezzanine block diagram 
1.2 Interface Topology 
Figure 1 above shows the full topology of the GbE interface, including maximum link lengths.  
Detailed design information for the motherboard and tray backplane is available upon request. 



 
2 October 30, 2014 
 
2 Interface Connector 
The connector interfaces between the NIC mezzanine card and the motherboard use the Samtec 
SEARAY solution. The mezzanine card uses a Samtec SEAM (male) connector and interfaces to the 
motherboard through a SEAF (female) connector. Table 1 lists the manufacturing part numbers 
(MPNs). 
Table 1: Connector manufacturing part numbers 
Manufacturer Mezzanine card connector MPN Mating (MB) connector MPN 
Samtec SEAM-20-03.5-S-08-2-A-K-TR SEAF-20-06.5-S-08-2-A-K-TR 
Molex 45970-2385 45971-2385 
The stackup height of the SEAM is 10mm, with a 6.5mm SEAF and a 3.5mm SEAM connector. In this 
configuration, it is expected that taller components would be place on the top side of the printed 
circuit board (PCB), as shown below in Figure 2. 
SEAF6.5mm
3.5mm
10mm
Device
Heatsink
Backside Keepout
SEAM
 
Figure 2: Connector stackup example 
2.1 Signal Definitions 
Table 2 defines the signals used in the NIC mezzanine interface. 



Open Compute Project  Open CloudServer OCS NIC Mezzanine 
http://opencompute.org 3 
 
Table 2: NIC mezzanine connector signal definitions 
Bus type I/O Logic Description 
P3E_CPU1_LAN_RX_DP/N[7:0] O 
Current-
mode 
logic 
(CML) 
PCIe Gen3 from the NIC mezzanine card to the 
CPU 
P3E_CPU1_LAN_TX_DP/N[7:0] I CML PCIe Gen3 from the CPU to the NIC mezzanine 
card 
CLK_100M_NIC_PE_DP/N I CML 100MHz PCIe Clock 
PCIE_RESET_N I 3.3V PCIe Reset 
MEZZ_PRESENT_N O 3.3V Mezz Present – Should be GND on mezzanine 
card 
NWK_1_TX[0]P/N O CML Port 1 GbE Transmit from mezzanine card to 
motherboard 
NWK_1_RX[0]P/N I CML Port 1 GbE Receive from motherboard to 
mezzanine card 
NWK_2_TX[0]P/N O CML Port 2 GbE Transmit from mezzanine card to 
motherboard 
NWK_2_RX[0]P/N I CML Port 2 GbE Receive from motherboard to 
mezzanine card 
NCSI_TXD[1:0] O 
Low 
Voltage 
Transistor 
Transistor 
Logic 
(LVTTL) 
Network Connectivity Status Indicator (NCSI) 
Transmit Data[1:0] from NIC to Baseboard 
Management Controller (BMC) 
NCSI_RXD[1:0] I LVTTL NCSI Transmit Data[1:0] from BMC to NIC 
NCSI_CLK_IN I LVTTL NCSI Input Clock 
NCSI_CRS_DV I LVTTL 
NCSI Receive Data Valid 
Connects to Management Controller Transmit 
Enable 
NCSI_RX_ER I LVTTL NCSI Receive Error 
NWK1_ACT_LED O 3.3V Port 1 Activity LED 
NWK1_LINK_LED O 3.3V Port 1 Link LED 
NWK2_ACT_LED O 3.3V Port 2 Activity LED 
NWK2_LINK_LED O 3.3V Port 2 Link LED 
SMB_ALERT_N O 3.3V I2C Alert from NIC mezzanine card to BMC 



 
4 October 30, 2014 
 
Bus type I/O Logic Description 
NWK1_PRESENT_N I 3.3V Port 1 Cable Present Indicator 
NWK1_I2C_SDA I/O 3.3V Port1 I2C Data to Cable 
NWK1_I2C_CLK O 3.3V Port 1 I2C Clock to Cable 
NWK2_PRESENT_N I 3.3V Port 2 Cable Present Indicator 
NWK2_I2C_SDA I/O 3.3V Port 2 I2C Data to Cable 
NWK2_I2C_SCL O 3.3V Port 2 I2C Clock to Cable 
PCIE_WAKE_N O 3.3V PCIe Wake 
SMB_SCL I 3.3V I2C to BMC 
SMB_SDA I/O 3.3V I2C to BMC 
NIC_MEZZ_ID[1:0] O 3.3V 
NIC mezzanine ID , connected to BMC on 
motherboard 
NIC_MEZZ_ID[1:0] definition is: 
0:0 = Mellanox 10G 
0:1 = Custom Mellanox 10G 
1:0 = Emulex 10G 
1:1 = Future 10G 
P3V3 I 3.3V 3.3V Input Power 
P3V3_AUX I 3.3V 3.3V Aux Input Power 
P12V_AUX I 12V 12V Input Power 
Ground   Ground pins 



Open Compute Project  Open CloudServer OCS NIC Mezzanine 
http://opencompute.org 5 
2.2 Connector Pinout 
Table 3 lists the pinout for the 160-pin NIC mezzanine connector. 
Table 3: NIC mezzanine connector pinout 
 
1 GND PCIE_RESET_N GND PCIE_WAKE_N NIC_MEZZ_ID0 SMB_ALERT_N GND CLK_100M_NIC_PE_DP 8
9 P3E_CPU1_LAN_TX_DP<0> GND P3E_CPU1_LAN_RX_DP<7> GND SMB_SCL NWK2_PRESENT_N GND CLK_100M_NIC_PE_DN 16
17 P3E_CPU1_LAN_TX_DN<0> GND P3E_CPU1_LAN_RX_DN<7> GND SMB_SDA GND MEZZ_PRESENT_N GND 24
25 GND P3E_CPU1_LAN_TX_DP<1> GND P3E_CPU1_LAN_RX_DP<6> GND NCSI_TXD_0 GND NWK_2_TX0P 32
33 GND P3E_CPU1_LAN_TX_DN<1> GND P3E_CPU1_LAN_RX_DN<6> GND NCSI_TXD_1 GND NWK_2_TX0N 40
41 P3E_CPU1_LAN_TX_DP<2> GND P3E_CPU1_LAN_RX_DP<5> GND NCSI_RXD_0 GND NWK_2_TX1P GND 48
49 P3E_CPU1_LAN_TX_DN<2> GND P3E_CPU1_LAN_RX_DN<5> GND NCSI_RXD_1 GND NWK_2_TX1N GND 56
57 GND P3E_CPU1_LAN_TX_DP<3> GND P3E_CPU1_LAN_RX_DP<4> GND NCSI_TX_EN GND NWK_2_TX2P 64
65 GND P3E_CPU1_LAN_TX_DN<3> GND P3E_CPU1_LAN_RX_DN<4> GND NCSI_CLK_IN GND NWK_2_TX2N 72
73 P3E_CPU1_LAN_TX_DP<4> GND P3E_CPU1_LAN_RX_DP<0> GND NCSI_CRS_DV GND NWK_2_TX3P GND 80
81 P3E_CPU1_LAN_TX_DN<4> GND P3E_CPU1_LAN_RX_DN<0> GND NCSI_RX_ER GND NWK_2_TX3N GND 88
89 GND P3E_CPU1_LAN_TX_DP<5> GND P3E_CPU1_LAN_RX_DP<1> GND NWK_1_ACT_LED GND NWK_2_RX0P 96
97 GND P3E_CPU1_LAN_TX_DN<5> GND P3E_CPU1_LAN_RX_DN<1> GND NWK_1_LINK_LED GND NWK_2_RX0N 104
105 P3E_CPU1_LAN_TX_DP<6> GND P3E_CPU1_LAN_RX_DP<2> GND NWK_2_ACT_LED GND NWK_2_RX1N GND 112
113 P3E_CPU1_LAN_TX_DN<6> GND P3E_CPU1_LAN_RX_DN<2> GND NWK_2_LINK_LED GND NWK_2_RX1P GND 120
121 GND P3E_CPU1_LAN_TX_DP<7> GND P3E_CPU1_LAN_RX_DP<3> GND NWK_1_TX0P GND NWK_2_RX2N 128
129 NWK2_I2C_SDA P3E_CPU1_LAN_TX_DN<7> GND P3E_CPU1_LAN_RX_DN<3> GND NWK_1_TX0N GND NWK_2_RX2P 136
137 NWK2_I2C_SCL GND NIC_MEZZ_ID1 GND NWK_1_RX0P GND NWK_2_RX3N GND 144
145 P12V_AUX P3V3_AUX P3V3 GND NWK_1_RX0N GND NWK_2_RX3P NWK1_I2C_SDA 152
153 P12V_AUX P3V3_AUX P3V3 P3V3 GND NWK1_PRESENT_N GND NWK1_I2C_SCL 160



 
6 September 6, 2014 
2.3 Retimers/Repeaters 
The blade motherboard uses 10GbE – Texas Instruments DS110DF111 (or equivalent) single-
channel retimers/repeaters for interfacing to a passive cable. 
2.4 Power 
Table 4 shows the mezzanine power rates for each of the power rails.  Note that the maximum 
power consumption for of the mezzanine card is 25W. 
Table 4: NIC mezzanine power ratings 
Power rails Amps/pin  
(at 40oC) 
Total number of 
pins 
Power load capacity by 
connector pins (W) 
Motherboard limited 
power budget (W) 
12V_AUX 2A 2 43.2W 25.2W 
3.3V_AUX 2A 2 11.88W 1.2375W 
3.3V 2A 3 17.82W 9.9W 
Total power budget per mezzanine card 25W 
Figure 3 shows the mezzanine power-up sequence. Note that the reset will conform to the PCIe 
reset specification. 
 
Figure 3: NIC mezzanine power-up sequence 


Open Compute Project  Open CloudServer OCS NIC Mezzanine 
http://opencompute.org 7 
 
3 Mechanical Control Outline 
Figure 4 shows the mechanical outline requirements for the NIC mezzanine card. 
 
Figure 4: Mechanical control outline for the NIC mezzanine card 
4 CAD Model Capture 
Figure 5 shows the NIC mezzanine card installed in the blade assembly and indicates the direction 
of airflow.  


 
8 October 30, 2014 
 
 
Figure 5: NIC mezzanine, installed 
5 Thermal 
The mezzanine card is presented with an approaching airflow temperature of 70⁰C and a flow rate 
of 0.61m/s. No downstream airflow requirements are placed on the mezzanine card. 
6 Standoffs and Screws for Assembly 
The standoffs that hold the NIC mezzanine card on the motherboard are soldered, therefore the 
NIC mezzanine card manufacturer needs to supply only two 6-32 screws with the mezzanine cards. 
The screws are to be provided loose in a bag and secured during assembly of the card to the 
motherboard. 
